# SCM (Grand Teton) — schematic netlist excerpt (pin names and nets, part order shuffled) for the footprints in the layout excerpt that follows; sources: Cadence DE-HDL packaged netlist, KiCad conversion of 12092022_DA0F0TMDCD0_F0T_Management_Board_D_brd_V3_OCP.brd

R656  Q_RES  10K 1% EMPTY  pkg 0402LF  page 21 : A = P3V3_AUX ; B = EMMC_DT1_R
R498  Q_RES  22 1% CHIP  pkg 0402LF  page 46 : A = SPI_SYS_R_MOSI ; B = SPI_SYS_R1_MOSI

(kicad_pcb
	(version 20260206)
	(generator "pcbnew")
	(generator_version "10.0")
	(general
		(thickness 1.6)
		(legacy_teardrops no)
	)
	(paper "A4")
	(title_block
		(title "12092022_DA0F0TMDCD0_F0T_Management_Board_D_brd_V3_OCP.brd")
		(comment 1 "Grand Teton / footprints 322-323 of 1440")
	)
	(layers
		(0 "F.Cu" signal "TOP")
		(4 "In1.Cu" signal "GND")
		(6 "In2.Cu" signal "IN1")
		(8 "In3.Cu" signal "GND1")
		(10 "In4.Cu" signal "IN2")
		(12 "In5.Cu" signal "VCC")
		(14 "In6.Cu" signal "VCC1")
		(16 "In7.Cu" signal "IN3")
		(18 "In8.Cu" signal "GND2")
		(20 "In9.Cu" signal "IN4")
		(22 "In10.Cu" signal "GND3")
		(2 "B.Cu" signal "BOTTOM")
		(9 "F.Adhes" user "F.Adhesive")
		(11 "B.Adhes" user "B.Adhesive")
		(13 "F.Paste" user "Package Geometry/Pastemask Top")
		(15 "B.Paste" user "Package Geometry/Pastemask Bottom")
		(5 "F.SilkS" user "Ref Des/Silkscreen Top")
		(7 "B.SilkS" user "Ref Des/Silkscreen Bottom")
		(1 "F.Mask" user "Board Geometry/Soldermask Top")
		(3 "B.Mask" user "Board Geometry/Soldermask Bottom")
		(17 "Dwgs.User" user "User.Drawings")
		(19 "Cmts.User" user "User.Comments")
		(21 "Eco1.User" user "User.Eco1")
		(23 "Eco2.User" user "User.Eco2")
		(25 "Edge.Cuts" user "Board Geometry/Outline")
		(27 "Margin" user)
		(31 "F.CrtYd" user "Package Geometry/Place Bound Top")
		(29 "B.CrtYd" user "Package Geometry/Place Bound Bottom")
		(35 "F.Fab" user "Ref Des/Assembly Top")
		(33 "B.Fab" user "Ref Des/Assembly Bottom")
	)
	(footprint ""
		(layer "F.Cu")
		(at 36.047172 -83.816952 -90)
		(property "Reference" "R656"
			(at 0 0 270)
			(layer "F.SilkS")
			(hide yes)
			(effects
				(font
					(size 1.27 1.27)
				)
			)
		)
		(property "Value" ""
			(at 0 0 270)
			(layer "F.Fab")
			(effects
				(font
					(size 1.27 1.27)
				)
			)
		)
		(duplicate_pad_numbers_are_jumpers no)
		(fp_line
			(start -0.7874 0.4064)
			(end -0.7874 -0.4064)
			(stroke
				(width 0.1524)
				(type default)
			)
			(layer "F.SilkS")
		)
		(fp_line
			(start 0.7874 0.4064)
			(end -0.7874 0.4064)
			(stroke
				(width 0.1524)
				(type default)
			)
			(layer "F.SilkS")
		)
		(fp_line
			(start -0.7874 -0.4064)
			(end 0.7874 -0.4064)
			(stroke
				(width 0.1524)
				(type default)
			)
			(layer "F.SilkS")
		)
		(fp_line
			(start 0.7874 -0.4064)
			(end 0.7874 0.4064)
			(stroke
				(width 0.1524)
				(type default)
			)
			(layer "F.SilkS")
		)
		(fp_line
			(start -0.67945 0.3048)
			(end -0.67945 -0.305054)
			(stroke
				(width 0.1)
				(type default)
			)
			(layer "F.Fab")
		)
		(fp_line
			(start -0.12065 0.3048)
			(end -0.67945 0.3048)
			(stroke
				(width 0.1)
				(type default)
			)
			(layer "F.Fab")
		)
		(fp_line
			(start 0.120396 0.3048)
			(end 0.120396 0.2794)
			(stroke
				(width 0.1)
				(type default)
			)
			(layer "F.Fab")
		)
		(fp_line
			(start 0.67945 0.3048)
			(end 0.120396 0.3048)
			(stroke
				(width 0.1)
				(type default)
			)
			(layer "F.Fab")
		)
		(fp_line
			(start -0.12065 0.2794)
			(end -0.12065 0.3048)
			(stroke
				(width 0.1)
				(type default)
			)
			(layer "F.Fab")
		)
		(fp_line
			(start 0.120396 0.2794)
			(end -0.12065 0.2794)
			(stroke
				(width 0.1)
				(type default)
			)
			(layer "F.Fab")
		)
		(fp_line
			(start -0.12065 -0.2794)
			(end 0.12065 -0.2794)
			(stroke
				(width 0.1)
				(type default)
			)
			(layer "F.Fab")
		)
		(fp_line
			(start 0.12065 -0.2794)
			(end 0.12065 -0.3048)
			(stroke
				(width 0.1)
				(type default)
			)
			(layer "F.Fab")
		)
		(fp_line
			(start 0.12065 -0.3048)
			(end 0.67945 -0.3048)
			(stroke
				(width 0.1)
				(type default)
			)
			(layer "F.Fab")
		)
		(fp_line
			(start 0.67945 -0.3048)
			(end 0.67945 0.3048)
			(stroke
				(width 0.1)
				(type default)
			)
			(layer "F.Fab")
		)
		(fp_line
			(start -0.67945 -0.305054)
			(end -0.12065 -0.305054)
			(stroke
				(width 0.1)
				(type default)
			)
			(layer "F.Fab")
		)
		(fp_line
			(start -0.12065 -0.305054)
			(end -0.12065 -0.2794)
			(stroke
				(width 0.1)
				(type default)
			)
			(layer "F.Fab")
		)
		(pad "1" smd circle
			(at -0.40005 0 270)
			(size 0 0)
			(layers "F.Cu" "F.Mask" "F.Paste")
			(net "P3V3_AUX")
		)
		(pad "2" smd circle
			(at 0.40005 0 270)
			(size 0 0)
			(layers "F.Cu" "F.Mask" "F.Paste")
			(net "EMMC_DT1_R")
		)
	)
	(footprint ""
		(layer "F.Cu")
		(at 68.189094 -93.62694 180)
		(property "Reference" "R498"
			(at 0 0 180)
			(layer "F.SilkS")
			(hide yes)
			(effects
				(font
					(size 1.27 1.27)
				)
			)
		)
		(property "Value" ""
			(at 0 0 180)
			(layer "F.Fab")
			(effects
				(font
					(size 1.27 1.27)
				)
			)
		)
		(duplicate_pad_numbers_are_jumpers no)
		(fp_line
			(start 0.7874 0.4064)
			(end -0.7874 0.4064)
			(stroke
				(width 0.1524)
				(type default)
			)
			(layer "F.SilkS")
		)
		(fp_line
			(start 0.7874 -0.4064)
			(end 0.7874 0.4064)
			(stroke
				(width 0.1524)
				(type default)
			)
			(layer "F.SilkS")
		)
		(fp_line
			(start -0.7874 0.4064)
			(end -0.7874 -0.4064)
			(stroke
				(width 0.1524)
				(type default)
			)
			(layer "F.SilkS")
		)
		(fp_line
			(start -0.7874 -0.4064)
			(end 0.7874 -0.4064)
			(stroke
				(width 0.1524)
				(type default)
			)
			(layer "F.SilkS")
		)
		(fp_line
			(start 0.67945 0.3048)
			(end 0.120396 0.3048)
			(stroke
				(width 0.1)
				(type default)
			)
			(layer "F.Fab")
		)
		(fp_line
			(start 0.67945 -0.3048)
			(end 0.67945 0.3048)
			(stroke
				(width 0.1)
				(type default)
			)
			(layer "F.Fab")
		)
		(fp_line
			(start 0.12065 -0.2794)
			(end 0.12065 -0.3048)
			(stroke
				(width 0.1)
				(type default)
			)
			(layer "F.Fab")
		)
		(fp_line
			(start 0.12065 -0.3048)
			(end 0.67945 -0.3048)
			(stroke
				(width 0.1)
				(type default)
			)
			(layer "F.Fab")
		)
		(fp_line
			(start 0.120396 0.3048)
			(end 0.120396 0.2794)
			(stroke
				(width 0.1)
				(type default)
			)
			(layer "F.Fab")
		)
		(fp_line
			(start 0.120396 0.2794)
			(end -0.12065 0.2794)
			(stroke
				(width 0.1)
				(type default)
			)
			(layer "F.Fab")
		)
		(fp_line
			(start -0.12065 0.3048)
			(end -0.67945 0.3048)
			(stroke
				(width 0.1)
				(type default)
			)
			(layer "F.Fab")
		)
		(fp_line
			(start -0.12065 0.2794)
			(end -0.12065 0.3048)
			(stroke
				(width 0.1)
				(type default)
			)
			(layer "F.Fab")
		)
		(fp_line
			(start -0.12065 -0.2794)
			(end 0.12065 -0.2794)
			(stroke
				(width 0.1)
				(type default)
			)
			(layer "F.Fab")
		)
		(fp_line
			(start -0.12065 -0.305054)
			(end -0.12065 -0.2794)
			(stroke
				(width 0.1)
				(type default)
			)
			(layer "F.Fab")
		)
		(fp_line
			(start -0.67945 0.3048)
			(end -0.67945 -0.305054)
			(stroke
				(width 0.1)
				(type default)
			)
			(layer "F.Fab")
		)
		(fp_line
			(start -0.67945 -0.305054)
			(end -0.12065 -0.305054)
			(stroke
				(width 0.1)
				(type default)
			)
			(layer "F.Fab")
		)
		(pad "1" smd circle
			(at -0.40005 0 180)
			(size 0 0)
			(layers "F.Cu" "F.Mask" "F.Paste")
			(net "SPI_SYS_R_MOSI")
		)
		(pad "2" smd circle
			(at 0.40005 0 180)
			(size 0 0)
			(layers "F.Cu" "F.Mask" "F.Paste")
			(net "SPI_SYS_R1_MOSI")
		)
	)
)
